#ISCELL
  mstr_misc dns *
  *
#ISCELL
  pure_quanta quanta_title_block_c *
  *
#ISCELL
  pure_quanta_power universal_gnd *
  page193_i1
#ISCELL
  pure_quanta_power vcc_core *
  page193_i106
#ISCELL
  pure_quanta_power universal_gnd *
  page193_i107
#CELL
  pure_quanta q_cap *
  page193_i108
#CELL
  pure_quanta q_cap *
  page193_i109
#CELL
  pure_quanta q_cap *
  page193_i111
#CELL
  pure_quanta q_res *
  page193_i112
#CELL
  pure_quanta q_res *
  page193_i124
#ISCELL
  pure_quanta_power universal_gnd *
  page193_i125
#ISCELL
  pure_quanta_power vcc_core *
  page193_i126
#CELL
  pure_quanta q_cap *
  page193_i127
#CELL
  pure_quanta q_cap *
  page193_i128
#ISCELL
  pure_quanta_power universal_gnd *
  page193_i13
#CELL
  pure_quanta q_inductor4p_14 *
  page193_i137
#CELL
  pure_quanta q_inductor4p_14 *
  page193_i138
#CELL
  pure_quanta q_cap *
  page193_i139
#CELL
  pure_quanta q_res *
  page193_i14
#CELL
  pure_quanta q_cap *
  page193_i140
#CELL
  pure_quanta q_cap *
  page193_i141
#CELL
  pure_quanta q_res *
  page193_i142
#CELL
  pure_quanta q_cap *
  page193_i143
#CELL
  pure_quanta q_res *
  page193_i144
#ISCELL
  standard offpage *
  page193_i145
#ISCELL
  standard offpage *
  page193_i146
#ISCELL
  standard offpage *
  page193_i147
#CELL
  pure_quanta q_capp *
  page193_i148
#ISCELL
  pure_quanta_power universal_gnd *
  page193_i149
#ISCELL
  standard offpage *
  page193_i15
#CELL
  pure_quanta q_capp *
  page193_i150
#CELL
  pure_quanta q_capp *
  page193_i151
#ISCELL
  pure_quanta_power vcc_core *
  page193_i152
#CELL
  pure_quanta q_capp *
  page193_i153
#CELL
  pure_quanta q_cap *
  page193_i154
#CELL
  pure_quanta q_cap *
  page193_i155
#CELL
  pure_quanta q_cap *
  page193_i156
#ISCELL
  pure_quanta_power universal_gnd *
  page193_i157
#ISCELL
  pure_quanta_power universal_gnd *
  page193_i158
#CELL
  pure_quanta q_res *
  page193_i159
#ISCELL
  standard offpage *
  page193_i16
#CELL
  pure_quanta q_cap *
  page193_i160
#ISCELL
  pure_quanta_power vcc_core *
  page193_i161
#CELL
  pure_quanta q_cap *
  page193_i162
#ISCELL
  pure_quanta_power universal_gnd *
  page193_i163
#ISCELL
  pure_quanta_power universal_gnd *
  page193_i164
#CELL
  pure_quanta q_res *
  page193_i165
#CELL
  pure_quanta q_cap *
  page193_i166
#ISCELL
  pure_quanta_power universal_gnd *
  page193_i168
#ISCELL
  pure_quanta_power universal_gnd *
  page193_i169
#CELL
  pure_quanta q_capp *
  page193_i170
#ISCELL
  standard offpage *
  page193_i171
#ISCELL
  pure_quanta_power universal_gnd *
  page193_i172
#CELL
  pure_quanta q_res *
  page193_i173
#CELL
  pure_quanta q_cap *
  page193_i174
#ISCELL
  pure_quanta_power universal_gnd *
  page193_i175
#CELL
  pure_quanta q_res *
  page193_i176
#CELL
  pure_quanta q_cap *
  page193_i177
#ISCELL
  standard offpage *
  page193_i178
#CELL
  pure_quanta q_res *
  page193_i179
#ISCELL
  pure_quanta_power vcc_core *
  page193_i180
#CELL
  pure_quanta q_res *
  page193_i181
#ISCELL
  pure_quanta_power vcc_core *
  page193_i182
#ISCELL
  pure_quanta_power vcc_core *
  page193_i183
#CELL
  pure_quanta q_res *
  page193_i184
#ISCELL
  pure_quanta_power vcc_core *
  page193_i185
#ISCELL
  pure_quanta_power universal_gnd *
  page193_i19
#CELL
  pure_quanta q_res *
  page193_i2
#CELL
  pure_quanta isl99390frztr5935 *
  page193_i21
#CELL
  pure_quanta q_cap *
  page193_i23
#CELL
  pure_quanta q_cap *
  page193_i24
#ISCELL
  pure_quanta_power universal_gnd *
  page193_i25
#ISCELL
  standard offpage *
  page193_i27
#ISCELL
  standard offpage *
  page193_i28
#ISCELL
  standard offpage *
  page193_i3
#CELL
  pure_quanta q_cap *
  page193_i41
#CELL
  pure_quanta q_cap *
  page193_i46
#CELL
  pure_quanta q_cap *
  page193_i47
#ISCELL
  pure_quanta_power universal_gnd *
  page193_i48
#ISCELL
  pure_quanta_power vcc_core *
  page193_i49
#ISCELL
  standard offpage *
  page193_i5
#ISCELL
  standard offpage *
  page193_i6
#ISCELL
  pure_quanta_power universal_gnd *
  page193_i64
#CELL
  pure_quanta q_cap *
  page193_i65
#CELL
  pure_quanta q_cap *
  page193_i66
#CELL
  pure_quanta q_cap *
  page193_i67
#ISCELL
  pure_quanta_power vcc_core *
  page193_i73
#CELL
  pure_quanta q_capp *
  page193_i74
#CELL
  pure_quanta q_inductor *
  page193_i75
#CELL
  pure_quanta q_capp *
  page193_i76
#CELL
  pure_quanta isl99390frztr5935 *
  page193_i87
